(kicad_pcb
	(version 20260206)
	(generator "pcbnew")
	(generator_version "10.0")
	(general
		(thickness 1.6)
		(legacy_teardrops no)
	)
	(paper "A4")
	(title_block
		(title "04192023_DAF0TMB3IC0_F0TG_MB_C_brd_V02_OCP.brd")
		(comment 1 "Grand Teton / footprints 4436-4444 of 8354")
	)
	(layers
		(0 "F.Cu" signal "TOP")
		(4 "In1.Cu" signal "GND")
		(6 "In2.Cu" signal "IN1")
		(8 "In3.Cu" signal "GND1")
		(10 "In4.Cu" signal "IN2")
		(12 "In5.Cu" signal "GND2")
		(14 "In6.Cu" signal "IN3")
		(16 "In7.Cu" signal "GND3")
		(18 "In8.Cu" signal "VCC")
		(20 "In9.Cu" signal "VCC1")
		(22 "In10.Cu" signal "GND4")
		(24 "In11.Cu" signal "IN4")
		(26 "In12.Cu" signal "GND5")
		(28 "In13.Cu" signal "IN5")
		(30 "In14.Cu" signal "GND6")
		(32 "In15.Cu" signal "IN6")
		(34 "In16.Cu" signal "GND7")
		(2 "B.Cu" signal "BOTTOM")
		(9 "F.Adhes" user "F.Adhesive")
		(11 "B.Adhes" user "B.Adhesive")
		(13 "F.Paste" user "Package Geometry/Pastemask Top")
		(15 "B.Paste" user "Package Geometry/Pastemask Bottom")
		(5 "F.SilkS" user "Ref Des/Silkscreen Top")
		(7 "B.SilkS" user "Ref Des/Silkscreen Bottom")
		(1 "F.Mask" user "Board Geometry/Soldermask Top")
		(3 "B.Mask" user "Board Geometry/Soldermask Bottom")
		(17 "Dwgs.User" user "User.Drawings")
		(19 "Cmts.User" user "User.Comments")
		(21 "Eco1.User" user "User.Eco1")
		(23 "Eco2.User" user "User.Eco2")
		(25 "Edge.Cuts" user "Board Geometry/Outline")
		(27 "Margin" user)
		(31 "F.CrtYd" user "Package Geometry/Place Bound Top")
		(29 "B.CrtYd" user "Package Geometry/Place Bound Bottom")
		(35 "F.Fab" user "Ref Des/Assembly Top")
		(33 "B.Fab" user "Ref Des/Assembly Bottom")
	)
	(footprint ""
		(layer "F.Cu")
		(at 298.704 -108.966 -90)
		(property "Reference" "R1344"
			(at 0 0 270)
			(layer "F.SilkS")
			(hide yes)
			(effects
				(font
					(size 1.27 1.27)
				)
			)
		)
		(property "Value" ""
			(at 0 0 270)
			(layer "F.Fab")
			(effects
				(font
					(size 1.27 1.27)
				)
			)
		)
		(duplicate_pad_numbers_are_jumpers no)
		(fp_line
			(start -0.7874 0.4064)
			(end -0.7874 -0.4064)
			(stroke
				(width 0.1524)
				(type default)
			)
			(layer "F.SilkS")
		)
		(fp_line
			(start 0.7874 0.4064)
			(end -0.7874 0.4064)
			(stroke
				(width 0.1524)
				(type default)
			)
			(layer "F.SilkS")
		)
		(fp_line
			(start -0.7874 -0.4064)
			(end 0.7874 -0.4064)
			(stroke
				(width 0.1524)
				(type default)
			)
			(layer "F.SilkS")
		)
		(fp_line
			(start 0.7874 -0.4064)
			(end 0.7874 0.4064)
			(stroke
				(width 0.1524)
				(type default)
			)
			(layer "F.SilkS")
		)
		(fp_line
			(start -0.67945 0.3048)
			(end -0.67945 -0.305054)
			(stroke
				(width 0.1)
				(type default)
			)
			(layer "F.Fab")
		)
		(fp_line
			(start -0.12065 0.3048)
			(end -0.67945 0.3048)
			(stroke
				(width 0.1)
				(type default)
			)
			(layer "F.Fab")
		)
		(fp_line
			(start 0.120396 0.3048)
			(end 0.120396 0.2794)
			(stroke
				(width 0.1)
				(type default)
			)
			(layer "F.Fab")
		)
		(fp_line
			(start 0.67945 0.3048)
			(end 0.120396 0.3048)
			(stroke
				(width 0.1)
				(type default)
			)
			(layer "F.Fab")
		)
		(fp_line
			(start -0.12065 0.2794)
			(end -0.12065 0.3048)
			(stroke
				(width 0.1)
				(type default)
			)
			(layer "F.Fab")
		)
		(fp_line
			(start 0.120396 0.2794)
			(end -0.12065 0.2794)
			(stroke
				(width 0.1)
				(type default)
			)
			(layer "F.Fab")
		)
		(fp_line
			(start -0.12065 -0.2794)
			(end 0.12065 -0.2794)
			(stroke
				(width 0.1)
				(type default)
			)
			(layer "F.Fab")
		)
		(fp_line
			(start 0.12065 -0.2794)
			(end 0.12065 -0.3048)
			(stroke
				(width 0.1)
				(type default)
			)
			(layer "F.Fab")
		)
		(fp_line
			(start 0.12065 -0.3048)
			(end 0.67945 -0.3048)
			(stroke
				(width 0.1)
				(type default)
			)
			(layer "F.Fab")
		)
		(fp_line
			(start 0.67945 -0.3048)
			(end 0.67945 0.3048)
			(stroke
				(width 0.1)
				(type default)
			)
			(layer "F.Fab")
		)
		(fp_line
			(start -0.67945 -0.305054)
			(end -0.12065 -0.305054)
			(stroke
				(width 0.1)
				(type default)
			)
			(layer "F.Fab")
		)
		(fp_line
			(start -0.12065 -0.305054)
			(end -0.12065 -0.2794)
			(stroke
				(width 0.1)
				(type default)
			)
			(layer "F.Fab")
		)
		(pad "1" smd circle
			(at -0.40005 0 270)
			(size 0 0)
			(layers "F.Cu" "F.Mask" "F.Paste")
			(net "SMB_INA230_3V3AUX_SCL")
		)
		(pad "2" smd circle
			(at 0.40005 0 270)
			(size 0 0)
			(layers "F.Cu" "F.Mask" "F.Paste")
			(net "SMB_INA230_6_3V3AUX_SCL_R")
		)
	)
	(footprint ""
		(layer "F.Cu")
		(at 386.211826 -60.456318 180)
		(property "Reference" "R1630"
			(at 0 0 180)
			(layer "F.SilkS")
			(hide yes)
			(effects
				(font
					(size 1.27 1.27)
				)
			)
		)
		(property "Value" ""
			(at 0 0 180)
			(layer "F.Fab")
			(effects
				(font
					(size 1.27 1.27)
				)
			)
		)
		(duplicate_pad_numbers_are_jumpers no)
		(fp_line
			(start 0.7874 0.4064)
			(end -0.7874 0.4064)
			(stroke
				(width 0.1524)
				(type default)
			)
			(layer "F.SilkS")
		)
		(fp_line
			(start 0.7874 -0.4064)
			(end 0.7874 0.4064)
			(stroke
				(width 0.1524)
				(type default)
			)
			(layer "F.SilkS")
		)
		(fp_line
			(start -0.7874 0.4064)
			(end -0.7874 -0.4064)
			(stroke
				(width 0.1524)
				(type default)
			)
			(layer "F.SilkS")
		)
		(fp_line
			(start -0.7874 -0.4064)
			(end 0.7874 -0.4064)
			(stroke
				(width 0.1524)
				(type default)
			)
			(layer "F.SilkS")
		)
		(fp_line
			(start 0.67945 0.3048)
			(end 0.120396 0.3048)
			(stroke
				(width 0.1)
				(type default)
			)
			(layer "F.Fab")
		)
		(fp_line
			(start 0.67945 -0.3048)
			(end 0.67945 0.3048)
			(stroke
				(width 0.1)
				(type default)
			)
			(layer "F.Fab")
		)
		(fp_line
			(start 0.12065 -0.2794)
			(end 0.12065 -0.3048)
			(stroke
				(width 0.1)
				(type default)
			)
			(layer "F.Fab")
		)
		(fp_line
			(start 0.12065 -0.3048)
			(end 0.67945 -0.3048)
			(stroke
				(width 0.1)
				(type default)
			)
			(layer "F.Fab")
		)
		(fp_line
			(start 0.120396 0.3048)
			(end 0.120396 0.2794)
			(stroke
				(width 0.1)
				(type default)
			)
			(layer "F.Fab")
		)
		(fp_line
			(start 0.120396 0.2794)
			(end -0.12065 0.2794)
			(stroke
				(width 0.1)
				(type default)
			)
			(layer "F.Fab")
		)
		(fp_line
			(start -0.12065 0.3048)
			(end -0.67945 0.3048)
			(stroke
				(width 0.1)
				(type default)
			)
			(layer "F.Fab")
		)
		(fp_line
			(start -0.12065 0.2794)
			(end -0.12065 0.3048)
			(stroke
				(width 0.1)
				(type default)
			)
			(layer "F.Fab")
		)
		(fp_line
			(start -0.12065 -0.2794)
			(end 0.12065 -0.2794)
			(stroke
				(width 0.1)
				(type default)
			)
			(layer "F.Fab")
		)
		(fp_line
			(start -0.12065 -0.305054)
			(end -0.12065 -0.2794)
			(stroke
				(width 0.1)
				(type default)
			)
			(layer "F.Fab")
		)
		(fp_line
			(start -0.67945 0.3048)
			(end -0.67945 -0.305054)
			(stroke
				(width 0.1)
				(type default)
			)
			(layer "F.Fab")
		)
		(fp_line
			(start -0.67945 -0.305054)
			(end -0.12065 -0.305054)
			(stroke
				(width 0.1)
				(type default)
			)
			(layer "F.Fab")
		)
		(pad "1" smd circle
			(at -0.40005 0 180)
			(size 0 0)
			(layers "F.Cu" "F.Mask" "F.Paste")
			(net "PVDD18_S5_P0")
		)
		(pad "2" smd circle
			(at 0.40005 0 180)
			(size 0 0)
			(layers "F.Cu" "F.Mask" "F.Paste")
			(net "HDT_HDR_DBREQ_R_N")
		)
	)
	(footprint ""
		(layer "F.Cu")
		(at 277.352252 -116.10467)
		(property "Reference" "R1090"
			(at 0 0 0)
			(layer "F.SilkS")
			(hide yes)
			(effects
				(font
					(size 1.27 1.27)
				)
			)
		)
		(property "Value" ""
			(at 0 0 0)
			(layer "F.Fab")
			(effects
				(font
					(size 1.27 1.27)
				)
			)
		)
		(duplicate_pad_numbers_are_jumpers no)
		(fp_line
			(start -0.7874 -0.4064)
			(end 0.7874 -0.4064)
			(stroke
				(width 0.1524)
				(type default)
			)
			(layer "F.SilkS")
		)
		(fp_line
			(start -0.7874 0.4064)
			(end -0.7874 -0.4064)
			(stroke
				(width 0.1524)
				(type default)
			)
			(layer "F.SilkS")
		)
		(fp_line
			(start 0.7874 -0.4064)
			(end 0.7874 0.4064)
			(stroke
				(width 0.1524)
				(type default)
			)
			(layer "F.SilkS")
		)
		(fp_line
			(start 0.7874 0.4064)
			(end -0.7874 0.4064)
			(stroke
				(width 0.1524)
				(type default)
			)
			(layer "F.SilkS")
		)
		(fp_line
			(start -0.67945 -0.305054)
			(end -0.12065 -0.305054)
			(stroke
				(width 0.1)
				(type default)
			)
			(layer "F.Fab")
		)
		(fp_line
			(start -0.67945 0.3048)
			(end -0.67945 -0.305054)
			(stroke
				(width 0.1)
				(type default)
			)
			(layer "F.Fab")
		)
		(fp_line
			(start -0.12065 -0.305054)
			(end -0.12065 -0.2794)
			(stroke
				(width 0.1)
				(type default)
			)
			(layer "F.Fab")
		)
		(fp_line
			(start -0.12065 -0.2794)
			(end 0.12065 -0.2794)
			(stroke
				(width 0.1)
				(type default)
			)
			(layer "F.Fab")
		)
		(fp_line
			(start -0.12065 0.2794)
			(end -0.12065 0.3048)
			(stroke
				(width 0.1)
				(type default)
			)
			(layer "F.Fab")
		)
		(fp_line
			(start -0.12065 0.3048)
			(end -0.67945 0.3048)
			(stroke
				(width 0.1)
				(type default)
			)
			(layer "F.Fab")
		)
		(fp_line
			(start 0.120396 0.2794)
			(end -0.12065 0.2794)
			(stroke
				(width 0.1)
				(type default)
			)
			(layer "F.Fab")
		)
		(fp_line
			(start 0.120396 0.3048)
			(end 0.120396 0.2794)
			(stroke
				(width 0.1)
				(type default)
			)
			(layer "F.Fab")
		)
		(fp_line
			(start 0.12065 -0.3048)
			(end 0.67945 -0.3048)
			(stroke
				(width 0.1)
				(type default)
			)
			(layer "F.Fab")
		)
		(fp_line
			(start 0.12065 -0.2794)
			(end 0.12065 -0.3048)
			(stroke
				(width 0.1)
				(type default)
			)
			(layer "F.Fab")
		)
		(fp_line
			(start 0.67945 -0.3048)
			(end 0.67945 0.3048)
			(stroke
				(width 0.1)
				(type default)
			)
			(layer "F.Fab")
		)
		(fp_line
			(start 0.67945 0.3048)
			(end 0.120396 0.3048)
			(stroke
				(width 0.1)
				(type default)
			)
			(layer "F.Fab")
		)
		(pad "1" smd circle
			(at -0.40005 0)
			(size 0 0)
			(layers "F.Cu" "F.Mask" "F.Paste")
			(net "P3V3_AUX")
		)
		(pad "2" smd circle
			(at 0.40005 0)
			(size 0 0)
			(layers "F.Cu" "F.Mask" "F.Paste")
			(net "SMB_SENSOR_M2_P1_3V3AUX_SDA")
		)
	)
	(footprint ""
		(layer "F.Cu")
		(at 117.811296 -373.03583 -90)
		(property "Reference" "C1536"
			(at 0 0 270)
			(layer "F.SilkS")
			(hide yes)
			(effects
				(font
					(size 1.27 1.27)
				)
			)
		)
		(property "Value" ""
			(at 0 0 270)
			(layer "F.Fab")
			(effects
				(font
					(size 1.27 1.27)
				)
			)
		)
		(duplicate_pad_numbers_are_jumpers no)
		(fp_line
			(start -0.299974 0.150114)
			(end -0.299974 -0.150114)
			(stroke
				(width 0.1)
				(type default)
			)
			(layer "F.Fab")
		)
		(fp_line
			(start 0.299974 0.150114)
			(end -0.299974 0.150114)
			(stroke
				(width 0.1)
				(type default)
			)
			(layer "F.Fab")
		)
		(fp_line
			(start -0.299974 -0.150114)
			(end 0.299974 -0.150114)
			(stroke
				(width 0.1)
				(type default)
			)
			(layer "F.Fab")
		)
		(fp_line
			(start 0.299974 -0.150114)
			(end 0.299974 0.150114)
			(stroke
				(width 0.1)
				(type default)
			)
			(layer "F.Fab")
		)
		(pad "1" smd rect
			(at -0.2667 0 270)
			(size 0.3048 0.381)
			(layers "F.Cu" "F.Mask" "F.Paste")
			(net "P5E_CPU1_P3_TX_C_DN<5>")
		)
		(pad "2" smd rect
			(at 0.2667 0 270)
			(size 0.3048 0.381)
			(layers "F.Cu" "F.Mask" "F.Paste")
			(net "P5E_CPU1_P3_TX_DN<5>")
		)
	)
	(footprint ""
		(layer "F.Cu")
		(at 301.605696 -378.95403 -90)
		(property "Reference" "C926"
			(at 0 0 270)
			(layer "F.SilkS")
			(hide yes)
			(effects
				(font
					(size 1.27 1.27)
				)
			)
		)
		(property "Value" ""
			(at 0 0 270)
			(layer "F.Fab")
			(effects
				(font
					(size 1.27 1.27)
				)
			)
		)
		(duplicate_pad_numbers_are_jumpers no)
		(fp_line
			(start -0.299974 0.150114)
			(end -0.299974 -0.150114)
			(stroke
				(width 0.1)
				(type default)
			)
			(layer "F.Fab")
		)
		(fp_line
			(start 0.299974 0.150114)
			(end -0.299974 0.150114)
			(stroke
				(width 0.1)
				(type default)
			)
			(layer "F.Fab")
		)
		(fp_line
			(start -0.299974 -0.150114)
			(end 0.299974 -0.150114)
			(stroke
				(width 0.1)
				(type default)
			)
			(layer "F.Fab")
		)
		(fp_line
			(start 0.299974 -0.150114)
			(end 0.299974 0.150114)
			(stroke
				(width 0.1)
				(type default)
			)
			(layer "F.Fab")
		)
		(pad "1" smd rect
			(at -0.2667 0 270)
			(size 0.3048 0.381)
			(layers "F.Cu" "F.Mask" "F.Paste")
			(net "P5E_CPU0_P0_TX_C_DN<3>")
		)
		(pad "2" smd rect
			(at 0.2667 0 270)
			(size 0.3048 0.381)
			(layers "F.Cu" "F.Mask" "F.Paste")
			(net "P5E_CPU0_P0_TX_DN<3>")
		)
	)
	(footprint ""
		(layer "F.Cu")
		(at 42.527982 -387.764274)
		(property "Reference" "R599"
			(at 0 0 0)
			(layer "F.SilkS")
			(hide yes)
			(effects
				(font
					(size 1.27 1.27)
				)
			)
		)
		(property "Value" ""
			(at 0 0 0)
			(layer "F.Fab")
			(effects
				(font
					(size 1.27 1.27)
				)
			)
		)
		(duplicate_pad_numbers_are_jumpers no)
		(fp_line
			(start -0.32512 -0.175006)
			(end 0.32512 -0.175006)
			(stroke
				(width 0.1)
				(type default)
			)
			(layer "F.Fab")
		)
		(fp_line
			(start -0.32512 0.175006)
			(end -0.32512 -0.175006)
			(stroke
				(width 0.1)
				(type default)
			)
			(layer "F.Fab")
		)
		(fp_line
			(start 0.32512 -0.175006)
			(end 0.32512 0.175006)
			(stroke
				(width 0.1)
				(type default)
			)
			(layer "F.Fab")
		)
		(fp_line
			(start 0.32512 0.175006)
			(end -0.32512 0.175006)
			(stroke
				(width 0.1)
				(type default)
			)
			(layer "F.Fab")
		)
		(pad "1" smd rect
			(at -0.2667 0)
			(size 0.3048 0.381)
			(layers "F.Cu" "F.Mask" "F.Paste")
			(net "CLK_100M_RETIMER_CPU1_P0_R_DP")
		)
		(pad "2" smd rect
			(at 0.2667 0 180)
			(size 0.3048 0.381)
			(layers "F.Cu" "F.Mask" "F.Paste")
			(net "CLK_100M_RETIMER_CPU1_P0_DP")
		)
	)
	(footprint ""
		(layer "F.Cu")
		(at 155.829 -111.76)
		(property "Reference" "C552"
			(at 0 0 0)
			(layer "F.SilkS")
			(hide yes)
			(effects
				(font
					(size 1.27 1.27)
				)
			)
		)
		(property "Value" ""
			(at 0 0 0)
			(layer "F.Fab")
			(effects
				(font
					(size 1.27 1.27)
				)
			)
		)
		(duplicate_pad_numbers_are_jumpers no)
		(fp_line
			(start -0.7874 -0.4064)
			(end 0.7874 -0.4064)
			(stroke
				(width 0.1524)
				(type default)
			)
			(layer "F.SilkS")
		)
		(fp_line
			(start -0.7874 0.4064)
			(end -0.7874 -0.4064)
			(stroke
				(width 0.1524)
				(type default)
			)
			(layer "F.SilkS")
		)
		(fp_line
			(start 0.7874 -0.4064)
			(end 0.7874 0.4064)
			(stroke
				(width 0.1524)
				(type default)
			)
			(layer "F.SilkS")
		)
		(fp_line
			(start 0.7874 0.4064)
			(end -0.7874 0.4064)
			(stroke
				(width 0.1524)
				(type default)
			)
			(layer "F.SilkS")
		)
		(fp_line
			(start -0.67945 -0.305054)
			(end -0.12065 -0.305054)
			(stroke
				(width 0.1)
				(type default)
			)
			(layer "F.Fab")
		)
		(fp_line
			(start -0.67945 0.3048)
			(end -0.67945 -0.305054)
			(stroke
				(width 0.1)
				(type default)
			)
			(layer "F.Fab")
		)
		(fp_line
			(start -0.12065 -0.305054)
			(end -0.12065 -0.2794)
			(stroke
				(width 0.1)
				(type default)
			)
			(layer "F.Fab")
		)
		(fp_line
			(start -0.12065 -0.2794)
			(end 0.12065 -0.2794)
			(stroke
				(width 0.1)
				(type default)
			)
			(layer "F.Fab")
		)
		(fp_line
			(start -0.12065 0.2794)
			(end -0.12065 0.3048)
			(stroke
				(width 0.1)
				(type default)
			)
			(layer "F.Fab")
		)
		(fp_line
			(start -0.12065 0.3048)
			(end -0.67945 0.3048)
			(stroke
				(width 0.1)
				(type default)
			)
			(layer "F.Fab")
		)
		(fp_line
			(start 0.120396 0.2794)
			(end -0.12065 0.2794)
			(stroke
				(width 0.1)
				(type default)
			)
			(layer "F.Fab")
		)
		(fp_line
			(start 0.120396 0.3048)
			(end 0.120396 0.2794)
			(stroke
				(width 0.1)
				(type default)
			)
			(layer "F.Fab")
		)
		(fp_line
			(start 0.12065 -0.3048)
			(end 0.67945 -0.3048)
			(stroke
				(width 0.1)
				(type default)
			)
			(layer "F.Fab")
		)
		(fp_line
			(start 0.12065 -0.2794)
			(end 0.12065 -0.3048)
			(stroke
				(width 0.1)
				(type default)
			)
			(layer "F.Fab")
		)
		(fp_line
			(start 0.67945 -0.3048)
			(end 0.67945 0.3048)
			(stroke
				(width 0.1)
				(type default)
			)
			(layer "F.Fab")
		)
		(fp_line
			(start 0.67945 0.3048)
			(end 0.120396 0.3048)
			(stroke
				(width 0.1)
				(type default)
			)
			(layer "F.Fab")
		)
		(pad "1" smd circle
			(at -0.40005 0)
			(size 0 0)
			(layers "F.Cu" "F.Mask" "F.Paste")
			(net "P1V8_AUX")
		)
		(pad "2" smd circle
			(at 0.40005 0)
			(size 0 0)
			(layers "F.Cu" "F.Mask" "F.Paste")
			(net "GND")
		)
	)
	(footprint ""
		(layer "F.Cu")
		(at 100.696268 -394.3604 -90)
		(property "Reference" "R749"
			(at 0 0 270)
			(layer "F.SilkS")
			(hide yes)
			(effects
				(font
					(size 1.27 1.27)
				)
			)
		)
		(property "Value" ""
			(at 0 0 270)
			(layer "F.Fab")
			(effects
				(font
					(size 1.27 1.27)
				)
			)
		)
		(duplicate_pad_numbers_are_jumpers no)
		(fp_line
			(start -0.32512 0.175006)
			(end -0.32512 -0.175006)
			(stroke
				(width 0.1)
				(type default)
			)
			(layer "F.Fab")
		)
		(fp_line
			(start 0.32512 0.175006)
			(end -0.32512 0.175006)
			(stroke
				(width 0.1)
				(type default)
			)
			(layer "F.Fab")
		)
		(fp_line
			(start -0.32512 -0.175006)
			(end 0.32512 -0.175006)
			(stroke
				(width 0.1)
				(type default)
			)
			(layer "F.Fab")
		)
		(fp_line
			(start 0.32512 -0.175006)
			(end 0.32512 0.175006)
			(stroke
				(width 0.1)
				(type default)
			)
			(layer "F.Fab")
		)
		(pad "1" smd rect
			(at -0.2667 0 270)
			(size 0.3048 0.381)
			(layers "F.Cu" "F.Mask" "F.Paste")
			(net "RST_RT_CPU1_P1_PERST_R_N")
		)
		(pad "2" smd rect
			(at 0.2667 0 90)
			(size 0.3048 0.381)
			(layers "F.Cu" "F.Mask" "F.Paste")
			(net "GND")
		)
	)
	(footprint ""
		(layer "F.Cu")
		(at 109.210602 -395.782038 90)
		(property "Reference" "R6734"
			(at 0 0 90)
			(layer "F.SilkS")
			(hide yes)
			(effects
				(font
					(size 1.27 1.27)
				)
			)
		)
		(property "Value" ""
			(at 0 0 90)
			(layer "F.Fab")
			(effects
				(font
					(size 1.27 1.27)
				)
			)
		)
		(duplicate_pad_numbers_are_jumpers no)
		(fp_line
			(start 0.32512 -0.175006)
			(end 0.32512 0.175006)
			(stroke
				(width 0.1)
				(type default)
			)
			(layer "F.Fab")
		)
		(fp_line
			(start -0.32512 -0.175006)
			(end 0.32512 -0.175006)
			(stroke
				(width 0.1)
				(type default)
			)
			(layer "F.Fab")
		)
		(fp_line
			(start 0.32512 0.175006)
			(end -0.32512 0.175006)
			(stroke
				(width 0.1)
				(type default)
			)
			(layer "F.Fab")
		)
		(fp_line
			(start -0.32512 0.175006)
			(end -0.32512 -0.175006)
			(stroke
				(width 0.1)
				(type default)
			)
			(layer "F.Fab")
		)
		(pad "1" smd rect
			(at -0.2667 0 90)
			(size 0.3048 0.381)
			(layers "F.Cu" "F.Mask" "F.Paste")
			(net "P1V8_CPU1_RT_1D")
		)
		(pad "2" smd rect
			(at 0.2667 0 270)
			(size 0.3048 0.381)
			(layers "F.Cu" "F.Mask" "F.Paste")
			(net "SMB_RT_CPU1_P1_ROM_R_SCL")
		)
	)
)
